FILE_TYPE = MULTI_PHYS_TABLE;

PART 'Q_XTAL_4P_13BI_24GND'

{========================================================================================}
:VALUE      | PART_TYPE | MATERIAL | PART_NUMBER    = STANDARD        | LIFECYCLE      | PART_NUMBER   | JEDEC_TYPE                     | ALT_SYMBOLS | DESCRIPTION                                | MANUFTR | MANUF_PN                               | RD_CMPLS_LVL | CMPLS_LVL | CLASS | DIP_SMD | FROM_PJ          | DATA                                           | FP_ECN           | EE_CHECK_LIST | STATUS | PSL | PREFERENCE | CREATOR | CREATEDAY  ;
{========================================================================================}
 '25MHZ'    | 'SMLF'    | 'MISC'   | 'BG625000030'(!) = ''              | ''             | 'BG625000030' |'X_7MXA'| ''          | 'XTAL SMD 25MHZ(+-30PPM,16PF)7M25000034'   | 'TXC'   | '7M25000034'                           | 'EP(V1)'     | 'EP(V1)'  | 'IO'  | ''      | 'T2H-GAVEN'      | 'TXC_7M25000034_REVA7.pdf'                     | ''               | ''            | ''     | ''  | ''         | ''      | '20141020'
 '25MHZ'    | 'SMLF'    | 'EMPTY'  | 'BG625000030'(!) = ''              | ''             | 'BG625000030' |'X_7MXA'| ''          | 'XTAL SMD 25MHZ(+-30PPM,16PF)7M25000034'   | 'TXC'   | '7M25000034'                           | 'EP(V1)'     | 'EP(V1)'  | 'IO'  | ''      | 'T2H-GAVEN'      | 'TXC_7M25000034_REVA7.pdf'                     | ''               | ''            | ''     | ''  | ''         | ''      | '20141020'
 '48MHZ'    | 'SMLF'    | 'MISC'   | 'BG648000003'(!) = ''              | ''             | 'BG648000003' |'X_7MXA'| ''          | 'XTAL SMD 48MHZ(15PPM,8PF)7M48000176'      | 'TXC'   | '7M48000176'                           | 'EP(V1)'     | 'EP(V1)'  | 'IO'  | ''      | 'T2H-GAVEN'      | 'TXC_7M48000176_REVA5.pdf'                     | ''               | ''            | ''     | ''  | ''         | ''      | '20141020'
 '48MHZ'    | 'SMLF'    | 'EMPTY'  | 'BG648000003'(!) = ''              | ''             | 'BG648000003' |'X_7MXA'| ''          | 'XTAL SMD 48MHZ(15PPM,8PF)7M48000176'      | 'TXC'   | '7M48000176'                           | 'EP(V1)'     | 'EP(V1)'  | 'IO'  | ''      | 'T2H-GAVEN'      | 'TXC_7M48000176_REVA5.pdf'                     | ''               | ''            | ''     | ''  | ''         | ''      | '20141020'
 '48MHZ'    | 'SMLF'    | 'MISC'   | 'BG648000039'(!) = ''              | ''             | 'BG648000039' |'X_7MXA'| ''          | 'XTAL SMD 48MHZ(30PPM,10PF)7M48020003'     | 'TXC'   | '7M48020003'                           | 'EP(V1)'     | ''        | 'IO'  | ''      | 'S6A-MEALY'      | 'TXC_7M48020003_REVS1.pdf'                     | ''               | ''            | ''     | ''  | ''         | ''      | '20141103'
 '48MHZ'    | 'SMLF'    | 'EMPTY'  | 'BG648000039'(!) = ''              | ''             | 'BG648000039' |'X_7MXA'| ''          | 'XTAL SMD 48MHZ(30PPM,10PF)7M48020003'     | 'TXC'   | '7M48020003'                           | 'EP(V1)'     | ''        | 'IO'  | ''      | 'S6A-MEALY'      | 'TXC_7M48020003_REVS1.pdf'                     | ''               | ''            | ''     | ''  | ''         | ''      | '20141103'
 '40MHZ'    | 'SMLF'    | 'MISC'   | 'BG640000005'(!) = ''              | ''             | 'BG640000005' |'X_4S_8Y40000010_2X1-6'| ''          | 'CRYSTAL 40MHZ(+-10PPM,8PF)8Y40000010'     | 'TXC'   | '8Y40000010'                           | 'EP(V1)'     | 'EP(V1)'  | 'IO'  | ''      | 'T2H-GAVEN'      | 'TXC_8Y40000010_REVS1.pdf'                     | ''               | ''            | ''     | ''  | ''         | ''      | '20141201'
 '40MHZ'    | 'SMLF'    | 'EMPTY'  | 'BG640000005'(!) = ''              | ''             | 'BG640000005' |'X_4S_8Y40000010_2X1-6'| ''          | 'CRYSTAL 40MHZ(+-10PPM,8PF)8Y40000010'     | 'TXC'   | '8Y40000010'                           | 'EP(V1)'     | 'EP(V1)'  | 'IO'  | ''      | 'T2H-GAVEN'      | 'TXC_8Y40000010_REVS1.pdf'                     | ''               | ''            | ''     | ''  | ''         | ''      | '20141201'
 '24MHZ'    | 'SMLF'    | 'MISC'   | 'BG624000101'(!) = ''              | ''             | 'BG624000101' |'X_7MXA'| ''          | 'XTAL SMD 24MHZ(+-30PPM,18PF)7M24020002'   | 'TXC'   | '7M24020002'                           | 'EP(V1)'     | ''        | 'IO'  | ''      | 'S3A-THOMAS'     | 'TXC_7M24020002_REVA1.pdf'                     | ''               | ''            | ''     | ''  | ''         | ''      | '20141230'
 '24MHZ'    | 'SMLF'    | 'EMPTY'  | 'BG624000101'(!) = ''              | ''             | 'BG624000101' |'X_7MXA'| ''          | 'XTAL SMD 24MHZ(+-30PPM,18PF)7M24020002'   | 'TXC'   | '7M24020002'                           | 'EP(V1)'     | ''        | 'IO'  | ''      | 'S3A-THOMAS'     | 'TXC_7M24020002_REVA1.pdf'                     | ''               | ''            | ''     | ''  | ''         | ''      | '20141230'
 '25MHZ'    | 'SMLF'    | 'MISC'   | 'BG625000802'(!) = ''              | ''             | 'BG625000802' |'X_7MXA'| ''          | 'XTAL SMD 25MHZ(+-20PPM,20PF)7M25020008'   | 'TXC'   | '7M25020008'                           | 'EP(V1)'     | 'EP(V1)'  | 'IO'  | ''      | 'S5M-GLEN'       | 'TXC_7M25020008_REVA1.pdf'                     | ''               | ''            | ''     | ''  | ''         | ''      | '20150112'
 '25MHZ'    | 'SMLF'    | 'EMPTY'  | 'BG625000802'(!) = ''              | ''             | 'BG625000802' |'X_7MXA'| ''          | 'XTAL SMD 25MHZ(+-20PPM,20PF)7M25020008'   | 'TXC'   | '7M25020008'                           | 'EP(V1)'     | 'EP(V1)'  | 'IO'  | ''      | 'S5M-GLEN'       | 'TXC_7M25020008_REVA1.pdf'                     | ''               | ''            | ''     | ''  | ''         | ''      | '20150112'
 '25MHZ'    | 'SMLF'    | 'MISC'   | 'BG625000037'(!) = ''              | ''             | 'BG625000037' |'OSC4_E3FB'| ''          | 'XTAL SMD25MHZ(10PF,20PPM) Q22FA238004990' | 'SEG'   | 'Q22FA2380049900'                      | 'EU'         | 'EU'      | 'IO'  | ''      | 'F20A-CHAN-DER'  | 'SEG_Q22FA2380049900.pdf'                      | ''               | ''            | ''     | ''  | ''         | ''      | '20150706'
 '25MHZ'    | 'SMLF'    | 'EMPTY'  | 'BG625000037'(!) = ''              | ''             | 'BG625000037' |'OSC4_E3FB'| ''          | 'XTAL SMD25MHZ(10PF,20PPM) Q22FA238004990' | 'SEG'   | 'Q22FA2380049900'                      | 'EU'         | 'EU'      | 'IO'  | ''      | 'F20A-CHAN-DER'  | 'SEG_Q22FA2380049900.pdf'                      | ''               | ''            | ''     | ''  | ''         | ''      | '20150706'
 '33.33MHZ' | 'SMLF'    | 'MISC'   | 'BG633330000'(!) = ''              | ''             | 'BG633330000' |'X_7MXA'| ''          | 'XTAL SMD 33.33MHZ(12PF,20PPM)7M33300004'  | 'TXC'   | '7M33300004'                           | 'EP(V1)'     | ''        | 'IO'  | ''      | 'S5B-ROSSI'      | 'TXC_7M33300004.pdf'                           | ''               | ''            | ''     | ''  | ''         | ''      | '20151126'
 '33.33MHZ' | 'SMLF'    | 'EMPTY'  | 'BG633330000'(!) = ''              | ''             | 'BG633330000' |'X_7MXA'| ''          | 'XTAL SMD 33.33MHZ(12PF,20PPM)7M33300004'  | 'TXC'   | '7M33300004'                           | 'EP(V1)'     | ''        | 'IO'  | ''      | 'S5B-ROSSI'      | 'TXC_7M33300004.pdf'                           | ''               | ''            | ''     | ''  | ''         | ''      | '20151126'
 '12MHZ'    | 'SMLF'    | 'MISC'   | 'BG612000014'(!) = ''              | ''             | 'BG612000014' |'OSC4_E3FB'| ''          | 'XTAL 12MHZ(20PPM,10PF)E3SB12.0000F10E22'  | 'HHE'   | 'E3SB12.0000F10E22'                    | 'EP(V1)'     | 'EP(V1)'  | 'IO'  | ''      | 'S2S-LOUISE'     | 'HHE_E3SB12.0000F10E22.pdf'                    | ''               | ''            | ''     | ''  | ''         | ''      | '20151207'
 '12MHZ'    | 'SMLF'    | 'EMPTY'  | 'BG612000014'(!) = ''              | ''             | 'BG612000014' |'OSC4_E3FB'| ''          | 'XTAL 12MHZ(20PPM,10PF)E3SB12.0000F10E22'  | 'HHE'   | 'E3SB12.0000F10E22'                    | 'EP(V1)'     | 'EP(V1)'  | 'IO'  | ''      | 'S2S-LOUISE'     | 'HHE_E3SB12.0000F10E22.pdf'                    | ''               | ''            | ''     | ''  | ''         | ''      | '20151207'
 '12MHZ'    | 'SMLF'    | 'MISC'   | 'BG612000107'(!) = ''              | ''             | 'BG612000107' |'X_4S_FL4000120_3-2X2-5'| ''          | 'XTAL SMD 12MHZ(12PF,10PPM)AEC'            | 'ERC'   | 'FL1200151Q'                           | 'EP(V1)'     | ''        | 'IO'  | ''      | 'T2HV-RONNY'     | 'ERC_FL1200151Q_verA.pdf'                      | ''               | ''            | ''     | ''  | ''         | ''      | '20151222'
 '12MHZ'    | 'SMLF'    | 'EMPTY'  | 'BG612000107'(!) = ''              | ''             | 'BG612000107' |'X_4S_FL4000120_3-2X2-5'| ''          | 'XTAL SMD 12MHZ(12PF,10PPM)AEC'            | 'ERC'   | 'FL1200151Q'                           | 'EP(V1)'     | ''        | 'IO'  | ''      | 'T2HV-RONNY'     | 'ERC_FL1200151Q_verA.pdf'                      | ''               | ''            | ''     | ''  | ''         | ''      | '20151222'
 '25MHZ'    | 'SMLF'    | 'MISC'   | 'BG6250000B9'(!) = ''              | ''             | 'BG6250000B9' |'X_4S_FL4000120_3-2X2-5'| ''          | 'XTAL SMD 25MHZ(18PF,20PPM)FL2500333'      | 'ERC'   | 'FL2500333'                            | 'EP(V1)'     | 'EP(V1)'  | 'IO'  | ''      | 'T2HV-RONNY'     | 'ERC_FL2500333.pdf'                            | ''               | ''            | ''     | ''  | ''         | ''      | '20160115'
 '25MHZ'    | 'SMLF'    | 'EMPTY'  | 'BG6250000B9'(!) = ''              | ''             | 'BG6250000B9' |'X_4S_FL4000120_3-2X2-5'| ''          | 'XTAL SMD 25MHZ(18PF,20PPM)FL2500333'      | 'ERC'   | 'FL2500333'                            | 'EP(V1)'     | 'EP(V1)'  | 'IO'  | ''      | 'T2HV-RONNY'     | 'ERC_FL2500333.pdf'                            | ''               | ''            | ''     | ''  | ''         | ''      | '20160115'
 '25MHZ'    | 'SMLF'    | 'MISC'   | 'BG625000186'(!) = ''              | ''             | 'BG625000186' |'X_4S_FL4000120_3-2X2-5'| ''          | 'XTAL SMD 25MHZ(20PF,20PPM)FL2500157'      | 'ERC'   | 'FL2500157'                            | 'EP(V1)'     | ''        | 'IO'  | ''      | 'T2HV-RONNY'     | 'ERC_FL2500157.pdf'                            | ''               | ''            | ''     | ''  | ''         | ''      | '20160201'
 '25MHZ'    | 'SMLF'    | 'EMPTY'  | 'BG625000186'(!) = ''              | ''             | 'BG625000186' |'X_4S_FL4000120_3-2X2-5'| ''          | 'XTAL SMD 25MHZ(20PF,20PPM)FL2500157'      | 'ERC'   | 'FL2500157'                            | 'EP(V1)'     | ''        | 'IO'  | ''      | 'T2HV-RONNY'     | 'ERC_FL2500157.pdf'                            | ''               | ''            | ''     | ''  | ''         | ''      | '20160201'
 '25MHZ'    | 'SMLF'    | 'MISC'   | 'BG625000174'(!) = ''              | ''             | 'BG625000174' |'X_4S_FL4000120_3-2X2-5'| ''          | 'XTAL SMD 25MHZ(+-20PPM,20PF)FL2500316Z'   | 'ERC'   | 'FL2500316Z'                           | 'EP(V1)'     | ''        | 'IO'  | ''      | 'F08-MARK'       | 'ERC_FL2500316Z_revA.pdf'                      | ''               | ''            | ''     | ''  | ''         | ''      | '20160203'
 '25MHZ'    | 'SMLF'    | 'EMPTY'  | 'BG625000174'(!) = ''              | ''             | 'BG625000174' |'X_4S_FL4000120_3-2X2-5'| ''          | 'XTAL SMD 25MHZ(+-20PPM,20PF)FL2500316Z'   | 'ERC'   | 'FL2500316Z'                           | 'EP(V1)'     | ''        | 'IO'  | ''      | 'F08-MARK'       | 'ERC_FL2500316Z_revA.pdf'                      | ''               | ''            | ''     | ''  | ''         | ''      | '20160203'
 '25MHZ'    | 'SMLF'    | 'MISC'   | 'BG625000322'(!) = ''              | ''             | 'BG625000322' |'X_4S_FL4000120_3-2X2-5'| ''          | 'XTAL SMD 25MHZ(18PF,20PPM)AEC'            | 'ERC'   | 'FL2500333Q'                           | 'EP(V1)'     | ''        | 'IO'  | ''      | 'T2HV-TING-HUNG' | 'ERC_FL2500333Q.pdf'                           | ''               | ''            | ''     | ''  | ''         | ''      | '20160302'
 '25MHZ'    | 'SMLF'    | 'EMPTY'  | 'BG625000322'(!) = ''              | ''             | 'BG625000322' |'X_4S_FL4000120_3-2X2-5'| ''          | 'XTAL SMD 25MHZ(18PF,20PPM)AEC'            | 'ERC'   | 'FL2500333Q'                           | 'EP(V1)'     | ''        | 'IO'  | ''      | 'T2HV-TING-HUNG' | 'ERC_FL2500333Q.pdf'                           | ''               | ''            | ''     | ''  | ''         | ''      | '20160302'
 '25MHZ'    | 'SMLF'    | 'MISC'   | 'BG625000321'(!) = ''              | ''             | 'BG625000321' |'X_4S_FL4000120_3-2X2-5'| ''          | 'XTAL SMD 25MHZ(20PF,20PPM)AEC'            | 'ERC'   | 'FL2500157Q'                           | 'EP(V1)'     | ''        | 'IO'  | ''      | 'T2HV-TING-HUNG' | 'ERC_FL2500157Q.pdf'                           | ''               | ''            | ''     | ''  | ''         | ''      | '20160302'
 '25MHZ'    | 'SMLF'    | 'EMPTY'  | 'BG625000321'(!) = ''              | ''             | 'BG625000321' |'X_4S_FL4000120_3-2X2-5'| ''          | 'XTAL SMD 25MHZ(20PF,20PPM)AEC'            | 'ERC'   | 'FL2500157Q'                           | 'EP(V1)'     | ''        | 'IO'  | ''      | 'T2HV-TING-HUNG' | 'ERC_FL2500157Q.pdf'                           | ''               | ''            | ''     | ''  | ''         | ''      | '20160302'
 '25MHZ'    | 'SMLF'    | 'MISC'   | 'BG625000189'(!) = ''              | ''             | 'BG625000189' |'X_7MXA'| ''          | 'XTAL SMD 25MHZ(18PF,20PPM)7M25000150'     | 'TXC'   | '7M25000150'                           | 'EP(V1)'     | ''        | 'IO'  | ''      | 'MF2-CHIH-CHIEH' | 'TXC_7M25000150.pdf'                           | ''               | ''            | ''     | ''  | ''         | ''      | '20160307'
 '25MHZ'    | 'SMLF'    | 'EMPTY'  | 'BG625000189'(!) = ''              | ''             | 'BG625000189' |'X_7MXA'| ''          | 'XTAL SMD 25MHZ(18PF,20PPM)7M25000150'     | 'TXC'   | '7M25000150'                           | 'EP(V1)'     | ''        | 'IO'  | ''      | 'MF2-CHIH-CHIEH' | 'TXC_7M25000150.pdf'                           | ''               | ''            | ''     | ''  | ''         | ''      | '20160307'
 '12MHZ'    | 'SMLF'    | 'MISC'   | 'BG612000108'(!) = ''              | ''             | 'BG612000108' |'X_4S_FL4000120_3-2X2-5'| ''          | 'XTAL SMD 12MHZ(12PF,10PPM)AEC'            | 'ERC'   | 'FL1200179Q'                           | 'EP(V1)'     | ''        | 'IO'  | ''      | 'T2HV-TING-HUNG' | 'ERC_FL1200179Q.pdf'                           | ''               | ''            | ''     | ''  | ''         | ''      | '20160308'
 '12MHZ'    | 'SMLF'    | 'EMPTY'  | 'BG612000108'(!) = ''              | ''             | 'BG612000108' |'X_4S_FL4000120_3-2X2-5'| ''          | 'XTAL SMD 12MHZ(12PF,10PPM)AEC'            | 'ERC'   | 'FL1200179Q'                           | 'EP(V1)'     | ''        | 'IO'  | ''      | 'T2HV-TING-HUNG' | 'ERC_FL1200179Q.pdf'                           | ''               | ''            | ''     | ''  | ''         | ''      | '20160308'
 '25MHZ'    | 'SMLF'    | 'MISC'   | 'BG625000195'(!) = ''              | ''             | 'BG625000195' |'X_4S_FY2500111'| ''          | 'XTAL SMD 25MHZ(20PF,20PPM)AEC'            | 'ERC'   | 'FY2500133Q'                           | 'EP(V1)'     | ''        | 'IO'  | ''      | 'T2HV-TING-HUNG' | 'ERC_FY2500133Q_VerA.pdf'                      | ''               | ''            | ''     | ''  | ''         | ''      | '20160315'
 '25MHZ'    | 'SMLF'    | 'EMPTY'  | 'BG625000195'(!) = ''              | ''             | 'BG625000195' |'X_4S_FY2500111'| ''          | 'XTAL SMD 25MHZ(20PF,20PPM)AEC'            | 'ERC'   | 'FY2500133Q'                           | 'EP(V1)'     | ''        | 'IO'  | ''      | 'T2HV-TING-HUNG' | 'ERC_FY2500133Q_VerA.pdf'                      | ''               | ''            | ''     | ''  | ''         | ''      | '20160315'
 '12MHZ'    | 'SMLF'    | 'MISC'   | 'BG612000109'(!) = ''              | ''             | 'BG612000109' |'X_4S_FY2500111'| ''          | 'XTAL SMD 12MHZ(18PF,10PPM)AEC'            | 'ERC'   | 'FY1200112Q'                           | 'EP(V1)'     | ''        | 'IO'  | ''      | 'T2HV-TING-HUNG' | 'ERC_FY1200112Q_VerA.pdf'                      | ''               | ''            | ''     | ''  | ''         | ''      | '20160315'
 '12MHZ'    | 'SMLF'    | 'EMPTY'  | 'BG612000109'(!) = ''              | ''             | 'BG612000109' |'X_4S_FY2500111'| ''          | 'XTAL SMD 12MHZ(18PF,10PPM)AEC'            | 'ERC'   | 'FY1200112Q'                           | 'EP(V1)'     | ''        | 'IO'  | ''      | 'T2HV-TING-HUNG' | 'ERC_FY1200112Q_VerA.pdf'                      | ''               | ''            | ''     | ''  | ''         | ''      | '20160315'
 '12MHZ'    | 'SMLF'    | 'MISC'   | 'BG612000023'(!) = ''              | ''             | 'BG612000023' |'OSC4_DNCA250000ETS_2-5X2_H26'| ''          | 'XTAL 12MHZ(30PPM,10PF)E2SB12.0000F10E33'  | 'HHE'   | 'E2SB12.0000F10E33'                    | 'EP(V1)'     | 'EP(V1)'  | 'IO'  | ''      | 'S2W-CHIN'       | 'HHE_E2SB12.0000F10E33.pdf'                    | ''               | ''            | ''     | ''  | ''         | ''      | '20160408'
 '12MHZ'    | 'SMLF'    | 'EMPTY'  | 'BG612000023'(!) = ''              | ''             | 'BG612000023' |'OSC4_DNCA250000ETS_2-5X2_H26'| ''          | 'XTAL 12MHZ(30PPM,10PF)E2SB12.0000F10E33'  | 'HHE'   | 'E2SB12.0000F10E33'                    | 'EP(V1)'     | 'EP(V1)'  | 'IO'  | ''      | 'S2W-CHIN'       | 'HHE_E2SB12.0000F10E33.pdf'                    | ''               | ''            | ''     | ''  | ''         | ''      | '20160408'
 '25MHZ'    | 'SMLF'    | 'MISC'   | 'BG625000196'(!) = ''              | ''             | 'BG625000196' |'X_7MXA'| ''          | 'XTAL SMD 25MHZ(10PF,10PPM)AEC'            | 'TXC'   | 'AM25000002'                           | 'EP(V1)'     | ''        | 'IO'  | ''      | 'T2HV-TING-HUNG' | 'TXC_AM25000002_REVA1.pdf'                     | ''               | ''            | ''     | ''  | ''         | ''      | '20160429'
 '25MHZ'    | 'SMLF'    | 'EMPTY'  | 'BG625000196'(!) = ''              | ''             | 'BG625000196' |'X_7MXA'| ''          | 'XTAL SMD 25MHZ(10PF,10PPM)AEC'            | 'TXC'   | 'AM25000002'                           | 'EP(V1)'     | ''        | 'IO'  | ''      | 'T2HV-TING-HUNG' | 'TXC_AM25000002_REVA1.pdf'                     | ''               | ''            | ''     | ''  | ''         | ''      | '20160429'
 '25MHZ'    | 'SMLF'    | 'MISC'   | 'BG625000197'(!) = ''              | ''             | 'BG625000197' |'X_7B'| ''          | 'XTAL SMD 25MHZ(16PF,20PPM)AEC'            | 'TXC'   | 'AB25000002'                           | 'EP(V1)'     | ''        | 'IO'  | ''      | 'S2W-CHIN'       | 'TXC_AB25000002_REVA3.pdf'                     | ''               | ''            | ''     | ''  | ''         | ''      | '20160429'
 '25MHZ'    | 'SMLF'    | 'EMPTY'  | 'BG625000197'(!) = ''              | ''             | 'BG625000197' |'X_7B'| ''          | 'XTAL SMD 25MHZ(16PF,20PPM)AEC'            | 'TXC'   | 'AB25000002'                           | 'EP(V1)'     | ''        | 'IO'  | ''      | 'S2W-CHIN'       | 'TXC_AB25000002_REVA3.pdf'                     | ''               | ''            | ''     | ''  | ''         | ''      | '20160429'
 '48MHZ'    | 'SMLF'    | 'MISC'   | 'BG648000044'(!) = ''              | ''             | 'BG648000044' |'X_7MXA'| ''          | 'XTAL SMD 48MHZ(10PF,30PPM)AEC'            | 'TXC'   | 'AM48000301'                           | 'EP(V1)'     | ''        | 'IO'  | ''      | 'T2HV-TING-HUNG' | 'TXC_AM48000301.pdf'                           | ''               | ''            | ''     | ''  | ''         | ''      | '20160515'
 '48MHZ'    | 'SMLF'    | 'EMPTY'  | 'BG648000044'(!) = ''              | ''             | 'BG648000044' |'X_7MXA'| ''          | 'XTAL SMD 48MHZ(10PF,30PPM)AEC'            | 'TXC'   | 'AM48000301'                           | 'EP(V1)'     | ''        | 'IO'  | ''      | 'T2HV-TING-HUNG' | 'TXC_AM48000301.pdf'                           | ''               | ''            | ''     | ''  | ''         | ''      | '20160515'
 '48MHZ'    | 'SMLF'    | 'MISC'   | 'BG648000046'(!) = ''              | ''             | 'BG648000046' |'OSC4_E3FB'| ''          | 'XTAL SMD 48MHZ(10PPM,12PF)E3SB48E000801E' | 'HHE'   | 'E3SB48E000801E'                       | 'EP(V1)'     | ''        | 'IO'  | ''      | 'T6MB-JOSEPH'    | 'HHE_E3SB48E000801E.pdf'                       | ''               | ''            | ''     | ''  | ''         | ''      | '20160811'
 '48MHZ'    | 'SMLF'    | 'EMPTY'  | 'BG648000046'(!) = ''              | ''             | 'BG648000046' |'OSC4_E3FB'| ''          | 'XTAL SMD 48MHZ(10PPM,12PF)E3SB48E000801E' | 'HHE'   | 'E3SB48E000801E'                       | 'EP(V1)'     | ''        | 'IO'  | ''      | 'T6MB-JOSEPH'    | 'HHE_E3SB48E000801E.pdf'                       | ''               | ''            | ''     | ''  | ''         | ''      | '20160811'
 '25MHZ'    | 'SMLF'    | 'MISC'   | 'BG625000210'(!) = ''              | ''             | 'BG625000210' |'X_4S_8Y40000010_2X1-6'| ''          | 'XTAL SMD 25MHZ(20PPM,10PF)8Y25000023'     | 'TXC'   | '8Y25000023'                           | 'EP(V1)'     | ''        | 'IO'  | ''      | 'T2HV-TING-HUNG' | 'TXC_8Y25000023.pdf'                           | ''               | ''            | ''     | ''  | ''         | ''      | '20161020'
 '25MHZ'    | 'SMLF'    | 'EMPTY'  | 'BG625000210'(!) = ''              | ''             | 'BG625000210' |'X_4S_8Y40000010_2X1-6'| ''          | 'XTAL SMD 25MHZ(20PPM,10PF)8Y25000023'     | 'TXC'   | '8Y25000023'                           | 'EP(V1)'     | ''        | 'IO'  | ''      | 'T2HV-TING-HUNG' | 'TXC_8Y25000023.pdf'                           | ''               | ''            | ''     | ''  | ''         | ''      | '20161020'
 '25MHZ'    | 'SMLF'    | 'MISC'   | 'BG625000067'(!) = 'End of Design' | 'End of Life'  | 'BG625000067' |'X_4S_E5SB25_5X3-2_EOL'| ''          | 'XTAL SMD 25MHZ(+-10PPM,20PF)E5SB25.0000F' | 'HHE'   | 'E5SB25.0000F20D11'                    | 'EP(V1)'     | 'EP(V1)'  | 'IO'  | ''      | 'JBEF-STAN'      | 'HHE_E5SB25.0000F20D11.pdf'                    | ''               | ''            | ''     | ''  | ''         | ''      | '20170606'
 '25MHZ'    | 'SMLF'    | 'EMPTY'  | 'BG625000067'(!) = 'End of Design' | 'End of Life'  | 'BG625000067' |'X_4S_E5SB25_5X3-2_EOL'| ''          | 'XTAL SMD 25MHZ(+-10PPM,20PF)E5SB25.0000F' | 'HHE'   | 'E5SB25.0000F20D11'                    | 'EP(V1)'     | 'EP(V1)'  | 'IO'  | ''      | 'JBEF-STAN'      | 'HHE_E5SB25.0000F20D11.pdf'                    | ''               | ''            | ''     | ''  | ''         | ''      | '20170606'
 '24MHZ'    | 'SMLF'    | 'MISC'   | 'BG624000132'(!) = ''              | ''             | 'BG624000132' |'X_7MXA'| ''          | 'XTAL SMD 24MHZ(8PF,30PPM)AEC'             | 'TXC'   | 'AM24000304'                           | 'EP(V1)'     | ''        | 'IO'  | ''      | 'T2HV-MARK'      | 'TXC_AM24000304.pdf'                           | ''               | ''            | ''     | ''  | ''         | ''      | '20170914'
 '24MHZ'    | 'SMLF'    | 'EMPTY'  | 'BG624000132'(!) = ''              | ''             | 'BG624000132' |'X_7MXA'| ''          | 'XTAL SMD 24MHZ(8PF,30PPM)AEC'             | 'TXC'   | 'AM24000304'                           | 'EP(V1)'     | ''        | 'IO'  | ''      | 'T2HV-MARK'      | 'TXC_AM24000304.pdf'                           | ''               | ''            | ''     | ''  | ''         | ''      | '20170914'
 '25MHZ'    | 'SMLF'    | 'MISC'   | 'BG625000203'(!) = ''              | ''             | 'BG625000203' |'X_7MXA'| ''          | 'XTAL SMD 25MHZ (10PPM,10PF)7M25000032'    | 'TXC'   | 'BG625000203'                          | 'EP(V1)'     | ''        | 'IO'  | ''      | 'JG1-TONY'       | 'TXC_7M25000032_revA3.pdf'                     | ''               | ''            | ''     | ''  | ''         | ''      | '20180730'
 '25MHZ'    | 'SMLF'    | 'EMPTY'  | 'BG625000203'(!) = ''              | ''             | 'BG625000203' |'X_7MXA'| ''          | 'XTAL SMD 25MHZ (10PPM,10PF)7M25000032'    | 'TXC'   | 'BG625000203'                          | 'EP(V1)'     | ''        | 'IO'  | ''      | 'JG1-TONY'       | 'TXC_7M25000032_revA3.pdf'                     | ''               | ''            | ''     | ''  | ''         | ''      | '20180730'
 '48MHZ'    | 'SMLF'    | 'MISC'   | 'BG648000041'(!) = ''              | ''             | 'BG648000041' |'X_4S_FL4000120_3-2X2-5'| ''          | 'XTAL SMD 48MHZ(10PPM,10PF)FL4800070'      | 'ERC'   | 'FL4800070'                            | 'EP(V1)'     | 'EP(V1)'  | 'IO'  | ''      | 'T2N-FRANK'      | 'ERC_FL4800070.pdf'                            | ''               | ''            | ''     | ''  | ''         | ''      | '20181002'
 '48MHZ'    | 'SMLF'    | 'EMPTY'  | 'BG648000041'(!) = ''              | ''             | 'BG648000041' |'X_4S_FL4000120_3-2X2-5'| ''          | 'XTAL SMD 48MHZ(10PPM,10PF)FL4800070'      | 'ERC'   | 'FL4800070'                            | 'EP(V1)'     | 'EP(V1)'  | 'IO'  | ''      | 'T2N-FRANK'      | 'ERC_FL4800070.pdf'                            | ''               | ''            | ''     | ''  | ''         | ''      | '20181002'
 '50MHZ'    | 'SMLF'    | 'MISC'   | 'BG650000012'(!) = ''              | ''             | 'BG650000012' |'OSC4_E3FB'| ''          | 'XTAL 50MHZ(19PF,+-15PPM) Q22FA2380181100' | 'SEG'   | 'Q22FA2380181100'                      | 'EP(V1)'     | 'EP(V1)'  | 'IO'  | ''      | 'S3A-KENG-HAUR'  | 'SEG_Q22FA2380181100.pdf'                      | ''               | ''            | ''     | ''  | ''         | ''      | '20181023'
 '50MHZ'    | 'SMLF'    | 'EMPTY'  | 'BG650000012'(!) = ''              | ''             | 'BG650000012' |'OSC4_E3FB'| ''          | 'XTAL 50MHZ(19PF,+-15PPM) Q22FA2380181100' | 'SEG'   | 'Q22FA2380181100'                      | 'EP(V1)'     | 'EP(V1)'  | 'IO'  | ''      | 'S3A-KENG-HAUR'  | 'SEG_Q22FA2380181100.pdf'                      | ''               | ''            | ''     | ''  | ''         | ''      | '20181023'
 '48MHZ'    | 'SMLF'    | 'MISC '  | 'BG648000055'(!) = ''              | ''             | 'BG648000055' |'X_4S_FL4000120_3-2X2-5'| ''          | 'XTAL SMD 48MHZ(10PPM,12PF)FL4800076'      | 'ERC'   | 'FL4800076'                            | 'EU(V1)'     | 'EU(V1)'  | 'IO'  | ''      | 'T6UA-HANK'      | 'ERC_FL4800076.pdf'                            | ''               | ''            | ''     | ''  | ''         | ''      | '20181024'
 '48MHZ'    | 'SMLF'    | 'EMPTY'  | 'BG648000055'(!) = ''              | ''             | 'BG648000055' |'X_4S_FL4000120_3-2X2-5'| ''          | 'XTAL SMD 48MHZ(10PPM,12PF)FL4800076'      | 'ERC'   | 'FL4800076'                            | 'EU(V1)'     | 'EU(V1)'  | 'IO'  | ''      | 'T6UA-HANK'      | 'ERC_FL4800076.pdf'                            | ''               | ''            | ''     | ''  | ''         | ''      | '20181024'
 '48MHZ'    | 'SMLF'    | 'MISC'   | 'BG648000073'(!) = ''              | ''             | 'BG648000073' |'X_7MXA'| ''          | 'XTAL SMD 48MHZ (12PF,10PPM)7M48000030'    | 'TXC'   | '7M48000030'                           | 'EP(V1)'     | ''        | 'IO'  | ''      | 'F0G-BELL'       | 'TXC_7M48000030.pdf'                           | ''               | ''            | ''     | ''  | ''         | ''      | '20191017'
 '48MHZ'    | 'SMLF'    | 'EMPTY'  | 'BG648000073'(!) = ''              | ''             | 'BG648000073' |'X_7MXA'| ''          | 'XTAL SMD 48MHZ (12PF,10PPM)7M48000030'    | 'TXC'   | '7M48000030'                           | 'EP(V1)'     | ''        | 'IO'  | ''      | 'F0G-BELL'       | 'TXC_7M48000030.pdf'                           | ''               | ''            | ''     | ''  | ''         | ''      | '20191017'
 '25MHZ'    | 'SMLF'    | 'MISC'   | 'BG6250000E0'(!) = ''              | ''             | 'BG6250000E0' |'X_7MXA'| ''          | 'XTAL SMD 25MHZ (20PF,10PPM)7M25000038'    | 'TXC'   | '7M25000038'                           | 'EP(V1)'     | ''        | 'IO'  | ''      | 'F0G-BELL'       | 'TXC_7M25000038.pdf'                           | ''               | ''            | ''     | ''  | ''         | ''      | '20191022'
 '25MHZ'    | 'SMLF'    | 'EMPTY'  | 'BG6250000E0'(!) = ''              | ''             | 'BG6250000E0' |'X_7MXA'| ''          | 'XTAL SMD 25MHZ (20PF,10PPM)7M25000038'    | 'TXC'   | '7M25000038'                           | 'EP(V1)'     | ''        | 'IO'  | ''      | 'F0G-BELL'       | 'TXC_7M25000038.pdf'                           | ''               | ''            | ''     | ''  | ''         | ''      | '20191022'
 '24MHZ'    | 'SMLF'    | 'MISC'   | 'BG6240000G4'(!) = ''              | ''             | 'BG6240000G4' |'X_4S_X1E000021069700_3-2X2-5'| ''          | 'XTAL SMD 24MHZ(16PF,10PPM)X1E00002101300' | 'SEG'   | 'X1E000021013000'                      | 'EP(V1)'     | 'EP(V1)'  | 'IO'  | ''      | 'S8A-LOUIS'      | 'SEG_X1E000021013000.pdf'                      | ''               | ''            | ''     | ''  | ''         | ''      | '20200603'
 '24MHZ'    | 'SMLF'    | 'EMPTY'  | 'BG6240000G4'(!) = ''              | ''             | 'BG6240000G4' |'X_4S_X1E000021069700_3-2X2-5'| ''          | 'XTAL SMD 24MHZ(16PF,10PPM)X1E00002101300' | 'SEG'   | 'X1E000021013000'                      | 'EP(V1)'     | 'EP(V1)'  | 'IO'  | ''      | 'S8A-LOUIS'      | 'SEG_X1E000021013000.pdf'                      | ''               | ''            | ''     | ''  | ''         | ''      | '20200603'
 '48MHZ'    | 'SMLF'    | 'MISC'   | 'BG648000076'(!) = ''              | ''             | 'BG648000076' |'X_4S_FL4000120_3-2X2-5'| ''          | 'XTAL SMD 48MHZ(10PPM, 12PF)FL4800106'     | 'DDS'   | 'FL4800106'                            | 'EP(V1)'     | 'EP(V1)'  | 'IO'  | ''      | 'T6UB-MC'        | 'DDS_FL4800106.pdf'                            | ''               | ''            | ''     | ''  | ''         | ''      | '20200831'
 '48MHZ'    | 'SMLF'    | 'EMPTY'  | 'BG648000076'(!) = ''              | ''             | 'BG648000076' |'X_4S_FL4000120_3-2X2-5'| ''          | 'XTAL SMD 48MHZ(10PPM, 12PF)FL4800106'     | 'DDS'   | 'FL4800106'                            | 'EP(V1)'     | 'EP(V1)'  | 'IO'  | ''      | 'T6UB-MC'        | 'DDS_FL4800106.pdf'                            | ''               | ''            | ''     | ''  | ''         | ''      | '20200831'
 '25MHZ'    | 'SMLF'    | 'MISC'   | 'BG6250000I0'(!) = ''              | ''             | 'BG6250000I0' |'X_4S_FL4000120_3-2X2-5'| ''          | 'XTAL SMD 25MHZ(+-10PPM,12PF)FL2500350'    | 'DDS'   | 'FL2500350'                            | 'EP(V1)'     | 'EP(V1)'  | 'IO'  | ''      | 'F0C-GARY'       | 'DDS_FL2500350.pdf'                            | ''               | ''            | ''     | ''  | ''         | ''      | '20200921'
 '25MHZ'    | 'SMLF'    | 'EMPTY'  | 'BG6250000I0'(!) = ''              | ''             | 'BG6250000I0' |'X_4S_FL4000120_3-2X2-5'| ''          | 'XTAL SMD 25MHZ(+-10PPM,12PF)FL2500350'    | 'DDS'   | 'FL2500350'                            | 'EP(V1)'     | 'EP(V1)'  | 'IO'  | ''      | 'F0C-GARY'       | 'DDS_FL2500350.pdf'                            | ''               | ''            | ''     | ''  | ''         | ''      | '20200921'
 '25MHZ'    | 'SMLF'    | 'MISC'   | 'BG625000188'(!) = ''              | ''             | 'BG625000188' |'X_4S_FL4000120_3-2X2-5'| ''          | 'XTAL SMD 25MHZ(12PF,25PPM)FL2500221'      | 'ERC'   | 'FL2500221'                            | 'EP(V1)'     | 'EP(V1)'  | 'IO'  | ''      | 'F0CE-TONY'      | 'ERC_FL2500221.pdf'                            | ''               | ''            | ''     | ''  | ''         | ''      | '20201127'
 '25MHZ'    | 'SMLF'    | 'EMPTY'  | 'BG625000188'(!) = ''              | ''             | 'BG625000188' |'X_4S_FL4000120_3-2X2-5'| ''          | 'XTAL SMD 25MHZ(12PF,25PPM)FL2500221'      | 'ERC'   | 'FL2500221'                            | 'EP(V1)'     | 'EP(V1)'  | 'IO'  | ''      | 'F0CE-TONY'      | 'ERC_FL2500221.pdf'                            | ''               | ''            | ''     | ''  | ''         | ''      | '20201127'
 '25MHZ'    | 'SMLF'    | 'MISC'   | 'BG6250000I2'(!) = ''              | ''             | 'BG6250000I2' |'OSC4_E3FB'| ''          | 'XTAL 25MHZ(+-10PPM,12PF)E3SB25E000010E'   | 'HHE'   | 'E3SB25E000010E'                       | 'EP(V1)'     | 'EP(V1)'  | 'IO'  | ''      | 'F0CE-TONY'      | 'HHE_E3SB25E000010E.pdf'                       | ''               | ''            | ''     | ''  | ''         | ''      | '20201127'
 '25MHZ'    | 'SMLF'    | 'EMPTY'  | 'BG6250000I2'(!) = ''              | ''             | 'BG6250000I2' |'OSC4_E3FB'| ''          | 'XTAL 25MHZ(+-10PPM,12PF)E3SB25E000010E'   | 'HHE'   | 'E3SB25E000010E'                       | 'EP(V1)'     | 'EP(V1)'  | 'IO'  | ''      | 'F0CE-TONY'      | 'HHE_E3SB25E000010E.pdf'                       | ''               | ''            | ''     | ''  | ''         | ''      | '20201127'
 '26MHZ'    | 'SMLF'    | 'MISC'   | 'BG626000049'(!) = ''              | ''             | 'BG626000049' |'X_4S_8Z25000020_2-5X2'| ''          | 'XTAL 26MHZ(10PPM,11PF)8Z26000054'         | 'TXC'   | '8Z26000054'                           | 'EP(V1)'     | 'EP(V1)'  | 'IO'  | ''      | 'S6Z-TOM'        | 'TXC_8Z26000054.pdf'                           | ''               | ''            | ''     | ''  | ''         | ''      | '20210222'
 '26MHZ'    | 'SMLF'    | 'EMPTY'  | 'BG626000049'(!) = ''              | ''             | 'BG626000049' |'X_4S_8Z25000020_2-5X2'| ''          | 'XTAL 26MHZ(10PPM,11PF)8Z26000054'         | 'TXC'   | '8Z26000054'                           | 'EP(V1)'     | 'EP(V1)'  | 'IO'  | ''      | 'S6Z-TOM'        | 'TXC_8Z26000054.pdf'                           | ''               | ''            | ''     | ''  | ''         | ''      | '20210222'
 '25MHZ'    | 'SMLF'    | 'MISC'   | 'BG625000171'(!) = ''              | ''             | 'BG625000171' |'OSC4_E3FB'| ''          | 'XTAL SMD 25MHZ(10PPM,20PF)E3SB25E000040E' | 'HHE'   | 'E3SB25E000040E'                       | 'EP(V1)'     | 'EP(V1)'  | 'IO'  | ''      | 'T6U-JEFF'       | 'HHE_E3SB25E000040E.pdf'                       | ''               | ''            | ''     | ''  | ''         | ''      | '20210304'
 '25MHZ'    | 'SMLF'    | 'EMPTY'  | 'BG625000171'(!) = ''              | ''             | 'BG625000171' |'OSC4_E3FB'| ''          | 'XTAL SMD 25MHZ(10PPM,20PF)E3SB25E000040E' | 'HHE'   | 'E3SB25E000040E'                       | 'EP(V1)'     | 'EP(V1)'  | 'IO'  | ''      | 'T6U-JEFF'       | 'HHE_E3SB25E000040E.pdf'                       | ''               | ''            | ''     | ''  | ''         | ''      | '20210304'
 '25MHZ'    | 'SMLF'    | 'MISC'   | 'BG625000225'(!) = ''              | ''             | 'BG625000225' |'X_4S_FL4000120_3-2X2-5'| ''          | 'XTAL SMD 25MHZ(10PPM,10PF)FL2500462'      | 'DDS'   | 'FL2500462'                            | 'EP(V1)'     | 'EP(V1)'  | 'IO'  | ''      | 'S8Z-JACK'       | 'DDS_FL2500462.pdf'                            | ''               | ''            | ''     | ''  | ''         | ''      | '20210922'
 '25MHZ'    | 'SMLF'    | 'EMPTY'  | 'BG625000225'(!) = ''              | ''             | 'BG625000225' |'X_4S_FL4000120_3-2X2-5'| ''          | 'XTAL SMD 25MHZ(10PPM,10PF)FL2500462'      | 'DDS'   | 'FL2500462'                            | 'EP(V1)'     | 'EP(V1)'  | 'IO'  | ''      | 'S8Z-JACK'       | 'DDS_FL2500462.pdf'                            | ''               | ''            | ''     | ''  | ''         | ''      | '20210922'
 '48MHZ'    | 'SMLF'    | 'MISC'   | 'BG648000096'(!) = ''              | ''             | 'BG648000096' |'X_4S_7M25000083_3-2X2-5'| ''          | 'XTAL SMD 48MHZ(10PPM,8PF)7M48072002'      | 'TXC'   | '7M48072002'                           | 'EP(V1)'     | 'EP(V1)'  | 'IO'  | ''      | 'S3B-CLAIRE'     | 'TXC_7M48072002.pdf'                           | ''               | ''            | ''     | ''  | ''         | ''      | '20210922'
 '48MHZ'    | 'SMLF'    | 'EMPTY'  | 'BG648000096'(!) = ''              | ''             | 'BG648000096' |'X_4S_7M25000083_3-2X2-5'| ''          | 'XTAL SMD 48MHZ(10PPM,8PF)7M48072002'      | 'TXC'   | '7M48072002'                           | 'EP(V1)'     | 'EP(V1)'  | 'IO'  | ''      | 'S3B-CLAIRE'     | 'TXC_7M48072002.pdf'                           | ''               | ''            | ''     | ''  | ''         | ''      | '20210922'
 '48MHZ'    | 'SMLF'    | 'MISC'   | 'BG648000085'(!) = ''              | ''             | 'BG648000085' |'X_4S_X1E000021069700_3-2X2-5'| ''          | 'XTAL SMD 48MHZ(10PPM,8PF)X1E0000211114'   | 'SEG'   | 'X1E000021111400'                      | 'EP(V1)'     | 'EP(V1)'  | 'IO'  | ''      | 'S3B-CLAIRE'     | 'SEG_X1E000021111400.pdf'                      | ''               | ''            | ''     | ''  | ''         | ''      | '20210923'
 '48MHZ'    | 'SMLF'    | 'EMPTY'  | 'BG648000085'(!) = ''              | ''             | 'BG648000085' |'X_4S_X1E000021069700_3-2X2-5'| ''          | 'XTAL SMD 48MHZ(10PPM,8PF)X1E0000211114'   | 'SEG'   | 'X1E000021111400'                      | 'EP(V1)'     | 'EP(V1)'  | 'IO'  | ''      | 'S3B-CLAIRE'     | 'SEG_X1E000021111400.pdf'                      | ''               | ''            | ''     | ''  | ''         | ''      | '20210923'
 '12MHZ'    | 'SMLF'    | 'MISC'   | 'BG6120000E0'(!) = ''              | ''             | 'BG6120000E0' |'OSC4_DNCA250000ETS_2-5X2_H26'| ''          | 'XTAL 12MHZ(+-20PPM,10PF)E2SB12E00000EE'   | 'HHE'   | 'E2SB12E00000EE'                       | 'EP(V1)'     | 'EP(V1)'  | 'IO'  | ''      | 'F0T-IVES'       | 'HHE_E2SB12E00000EE.pdf'                       | ''               | ''            | ''     | ''  | ''         | ''      | '20211029'
 '12MHZ'    | 'SMLF'    | 'EMPTY'  | 'BG6120000E0'(!) = ''              | ''             | 'BG6120000E0' |'OSC4_DNCA250000ETS_2-5X2_H26'| ''          | 'XTAL 12MHZ(+-20PPM,10PF)E2SB12E00000EE'   | 'HHE'   | 'E2SB12E00000EE'                       | 'EP(V1)'     | 'EP(V1)'  | 'IO'  | ''      | 'F0T-IVES'       | 'HHE_E2SB12E00000EE.pdf'                       | ''               | ''            | ''     | ''  | ''         | ''      | '20211029'
 '25MHZ'    | 'SMLF'    | 'MISC'   | 'BG6250000G6'(!) = ''              | ''             | 'BG6250000G6' |'X_4S_7M25000083_3-2X2-5'| ''          | 'XTAL SMD 25MHZ(+-30PPM,18PF)7M25020018'   | 'TXC'   | '7M25020018'                           | 'EP(V1)'     | 'EP(V1)'  | 'IO'  | ''      | 'S3B-BERNIE'     | 'TXC_7M25020018.pdf'                           | ''               | ''            | ''     | ''  | ''         | ''      | '20211118'
 '25MHZ'    | 'SMLF'    | 'EMPTY'  | 'BG6250000G6'(!) = ''              | ''             | 'BG6250000G6' |'X_4S_7M25000083_3-2X2-5'| ''          | 'XTAL SMD 25MHZ(+-30PPM,18PF)7M25020018'   | 'TXC'   | '7M25020018'                           | 'EP(V1)'     | 'EP(V1)'  | 'IO'  | ''      | 'S3B-BERNIE'     | 'TXC_7M25020018.pdf'                           | ''               | ''            | ''     | ''  | ''         | ''      | '20211118'
 '25MHZ'    | 'SMLF'    | 'MISC'   | 'BG6250000F0'(!) = ''              | ''             | 'BG6250000F0' |'X_4S_FL4000120_3-2X2-5'| ''          | 'XTAL SMD 25MHZ(+-10PPM,8PF)FL2500498'     | 'DDS'   | 'FL2500498'                            | 'EP(V1)'     | 'EP(V1)'  | 'IO'  | ''      | 'F0C-IVES'       | 'DDS_FL2500498.pdf'                            | ''               | ''            | ''     | ''  | ''         | ''      | '20211129'
 '25MHZ'    | 'SMLF'    | 'EMPTY'  | 'BG6250000F0'(!) = ''              | ''             | 'BG6250000F0' |'X_4S_FL4000120_3-2X2-5'| ''          | 'XTAL SMD 25MHZ(+-10PPM,8PF)FL2500498'     | 'DDS'   | 'FL2500498'                            | 'EP(V1)'     | 'EP(V1)'  | 'IO'  | ''      | 'F0C-IVES'       | 'DDS_FL2500498.pdf'                            | ''               | ''            | ''     | ''  | ''         | ''      | '20211129'
 '12MHZ'    | 'SMLF'    | 'MISC'   | 'BG6120000A5'(!) = 'End of Design' | 'Comp-Approve' | 'BG6120000A5' |'X_4S_FY2500111'| ''          | 'CRYSTAL SMD 12MHZ(+-10PPM,18PF)FY1200112' | 'ERC'   | 'FY1200112'                            | 'EP(V1)'     | 'EP(V1)'  | 'IO'  | ''      | 'T2M-MICHAEL'    | 'ERC_FY1200112.pdf'                            | ''               | ''            | ''     | ''  | ''         | ''      | '20220222'
 '12MHZ'    | 'SMLF'    | 'EMPTY'  | 'BG6120000A5'(!) = 'End of Design' | 'Comp-Approve' | 'BG6120000A5' |'X_4S_FY2500111'| ''          | 'CRYSTAL SMD 12MHZ(+-10PPM,18PF)FY1200112' | 'ERC'   | 'FY1200112'                            | 'EP(V1)'     | 'EP(V1)'  | 'IO'  | ''      | 'T2M-MICHAEL'    | 'ERC_FY1200112.pdf'                            | ''               | ''            | ''     | ''  | ''         | ''      | '20220222'
 '12MHZ'    | 'SMLF'    | 'MISC'   | 'BG612000104'(!) = ''              | ''             | 'BG612000104' |'X_7MXA'| ''          | 'XTAL SMD 12MHZ(+-20PPM,18PF)7M12020002'   | 'TXC'   | '7M12020002'                           | 'EP(V1)'     | 'EP(V1)'  | 'IO'  | ''      | 'T6U-STAN'       | 'TXC_7M12020002.pdf'                           | ''               | ''            | ''     | ''  | ''         | ''      | '20220225'
 '12MHZ'    | 'SMLF'    | 'EMPTY'  | 'BG612000104'(!) = ''              | ''             | 'BG612000104' |'X_7MXA'| ''          | 'XTAL SMD 12MHZ(+-20PPM,18PF)7M12020002'   | 'TXC'   | '7M12020002'                           | 'EP(V1)'     | 'EP(V1)'  | 'IO'  | ''      | 'T6U-STAN'       | 'TXC_7M12020002.pdf'                           | ''               | ''            | ''     | ''  | ''         | ''      | '20220225'
 '50MHZ'    | 'SMLF'    | 'MISC'   | 'BG650000045'(!) = ''              | ''             | 'BG650000045' |'X_4S_FL4000120_3-2X2-5'| ''          | 'XTAL SMD 50 MHZ(+-10PPM,10PF)FL5000149'   | 'DDS'   | 'FL5000149'                            | 'EP(V1)'     | ''        | 'IO'  | ''      | 'S7P-JIM'        | 'DDS_FL5000149.pdf'                            | ''               | ''            | ''     | ''  | ''         | ''      | '20220506'
 '50MHZ'    | 'SMLF'    | 'EMPTY'  | 'BG650000045'(!) = ''              | ''             | 'BG650000045' |'X_4S_FL4000120_3-2X2-5'| ''          | 'XTAL SMD 50 MHZ(+-10PPM,10PF)FL5000149'   | 'DDS'   | 'FL5000149'                            | 'EP(V1)'     | ''        | 'IO'  | ''      | 'S7P-JIM'        | 'DDS_FL5000149.pdf'                            | ''               | ''            | ''     | ''  | ''         | ''      | '20220506'
 '25MHZ'    | 'SMLF'    | 'MISC'   | 'BG6250000P6'(!) = ''              | ''             | 'BG6250000P6' |'X_4S_FA-128_2X1-6'| ''          | 'XTAL SMD 25 MHZ(+-30PPM,12PF)FA-128'      | 'SEG'   | 'FA-128 25.000000 MHZ 12.0 +30.0-30.0' | 'EP(V1)'     | ''        | 'IO'  | ''      | 'S8A-JOSH'       | 'SEG_FA-128 25.000000 MHz 12.0 +30.0-30.0.pdf' | ''               | ''            | ''     | ''  | ''         | ''      | '20220512'
 '25MHZ'    | 'SMLF'    | 'EMPTY'  | 'BG6250000P6'(!) = ''              | ''             | 'BG6250000P6' |'X_4S_FA-128_2X1-6'| ''          | 'XTAL SMD 25 MHZ(+-30PPM,12PF)FA-128'      | 'SEG'   | 'FA-128 25.000000 MHZ 12.0 +30.0-30.0' | 'EP(V1)'     | ''        | 'IO'  | ''      | 'S8A-JOSH'       | 'SEG_FA-128 25.000000 MHz 12.0 +30.0-30.0.pdf' | ''               | ''            | ''     | ''  | ''         | ''      | '20220512'
 '25MHZ'    | 'SMLF'    | 'MISC'   | 'BG6250000P3'(!) = ''              | ''             | 'BG6250000P3' |'X_4S_8Z25000020_2-5X2'| ''          | 'XTAL SMD 25 MHZ(+-30PPM,8PF)8Z25070018'   | 'TXC'   | '8Z25070018'                           | 'EP(V1)'     | ''        | 'IO'  | ''      | 'S7P-JIM'        | 'TXC_8Z25070018.pdf'                           | ''               | ''            | ''     | ''  | ''         | ''      | '20220510'
 '25MHZ'    | 'SMLF'    | 'EMPTY'  | 'BG6250000P3'(!) = ''              | ''             | 'BG6250000P3' |'X_4S_8Z25000020_2-5X2'| ''          | 'XTAL SMD 25 MHZ(+-30PPM,8PF)8Z25070018'   | 'TXC'   | '8Z25070018'                           | 'EP(V1)'     | ''        | 'IO'  | ''      | 'S7P-JIM'        | 'TXC_8Z25070018.pdf'                           | ''               | ''            | ''     | ''  | ''         | ''      | '20220510'
 '25MHZ'    | 'SMLF'    | 'MISC'   | 'BG6250000P1'(!) = ''              | ''             | 'BG6250000P1' |'X_4S_FA-128_2X1-6'| ''          | 'XTAL SMD 25 MHZ(+-10PPM,12PF)FA-128 25.0' | 'SEG'   | 'FA-128 25.000000 MHZ 12.0 +10.0-10.0' | 'EP(V1)'     | ''        | 'IO'  | ''      | 'MF6-JOSH'       | 'SEG_FA-128 25.000000 MHZ 12.0 +10.0-10.0.pdf' | ''               | ''            | ''     | ''  | ''         | ''      | '20220613'
 '25MHZ'    | 'SMLF'    | 'EMPTY'  | 'BG6250000P1'(!) = ''              | ''             | 'BG6250000P1' |'X_4S_FA-128_2X1-6'| ''          | 'XTAL SMD 25 MHZ(+-10PPM,12PF)FA-128 25.0' | 'SEG'   | 'FA-128 25.000000 MHZ 12.0 +10.0-10.0' | 'EP(V1)'     | ''        | 'IO'  | ''      | 'MF6-JOSH'       | 'SEG_FA-128 25.000000 MHZ 12.0 +10.0-10.0.pdf' | ''               | ''            | ''     | ''  | ''         | ''      | '20220613'
 '12MHZ'    | 'SMLF'    | 'MISC'   | 'BG6120000B0'(!) = ''              | ''             | 'BG6120000B0' |'X_4S_8Z25000020_2-5X2'| ''          | 'XTAL 12MHZ(+-20PPM,10PF)8Z12000006'       | 'TXC'   | '8Z12000006'                           | 'EP(V1)'     | 'EP(V1)'  | 'IO'  | ''      | 'F0TG-CART'      | 'TXC_8Z12000006.pdf'                           | '8Z12000006.msg' | ''            | ''     | ''  | ''         | ''      | '20220617'
 '12MHZ'    | 'SMLF'    | 'EMPTY'  | 'BG6120000B0'(!) = ''              | ''             | 'BG6120000B0' |'X_4S_8Z25000020_2-5X2'| ''          | 'XTAL 12MHZ(+-20PPM,10PF)8Z12000006'       | 'TXC'   | '8Z12000006'                           | 'EP(V1)'     | 'EP(V1)'  | 'IO'  | ''      | 'F0TG-CART'      | 'TXC_8Z12000006.pdf'                           | '8Z12000006.msg' | ''            | ''     | ''  | ''         | ''      | '20220617'
 '12MHZ'    | 'SMLF'    | 'MISC'   | 'BG6120000D3'(!) = ''              | ''             | 'BG6120000D3' |'X_4S_FL4000120_3-2X2-5'| ''          | 'XTAL SMD 12MHZ(+-10PPM,10PF)FL1200185'    | 'DDS'   | 'FL1200185'                            | 'EP(V1)'     | 'EP(V1)'  | 'IO'  | ''      | 'S3IS-VINCENT'   | 'DDS_FL1200185.pdf'                            | ''               | ''            | ''     | ''  | ''         | ''      | '20220620'
 '12MHZ'    | 'SMLF'    | 'EMPTY'  | 'BG6120000D3'(!) = ''              | ''             | 'BG6120000D3' |'X_4S_FL4000120_3-2X2-5'| ''          | 'XTAL SMD 12MHZ(+-10PPM,10PF)FL1200185'    | 'DDS'   | 'FL1200185'                            | 'EP(V1)'     | 'EP(V1)'  | 'IO'  | ''      | 'S3IS-VINCENT'   | 'DDS_FL1200185.pdf'                            | ''               | ''            | ''     | ''  | ''         | ''      | '20220620'
 '25MHZ'    | 'SMLF'    | 'MISC'   | 'BG6250000Q5'(!) = ''              | ''             | 'BG6250000Q5' |'X_4S_8Z25000020_2-5X2'| ''          | 'XTAL SMD 25MHZ(8PF,20PPM)8Z25070026'      | 'TXC'   | '8Z25070026'                           | 'EP(V1)'     | ''        | 'IO'  | ''      | 'S3I-NICK'       | 'TXC_8Z25070026.pdf'                           | '8Z25070026.msg' | ''            | ''     | ''  | ''         | ''      | '20220630'
 '25MHZ'    | 'SMLF'    | 'EMPTY'  | 'BG6250000Q5'(!) = ''              | ''             | 'BG6250000Q5' |'X_4S_8Z25000020_2-5X2'| ''          | 'XTAL SMD 25MHZ(8PF,20PPM)8Z25070026'      | 'TXC'   | '8Z25070026'                           | 'EP(V1)'     | ''        | 'IO'  | ''      | 'S3I-NICK'       | 'TXC_8Z25070026.pdf'                           | '8Z25070026.msg' | ''            | ''     | ''  | ''         | ''      | '20220630'
 '25MHZ'    | 'SMLF'    | 'MISC'   | 'BG6250000Q6'(!) = ''              | ''             | 'BG6250000Q6' |'X_4S_7M25000083_3-2X2-5'| ''          | 'XTAL SMD 25MHZ(10PF,20PPM)7M25000149'     | 'TXC'   | '7M25000149'                           | 'EP(V1)'     | ''        | 'IO'  | ''      | 'S3I-NICK'       | 'TXC_7M25000149.pdf'                           | '7M25000149.msg' | ''            | ''     | ''  | ''         | ''      | '20220630'
 '25MHZ'    | 'SMLF'    | 'EMPTY'  | 'BG6250000Q6'(!) = ''              | ''             | 'BG6250000Q6' |'X_4S_7M25000083_3-2X2-5'| ''          | 'XTAL SMD 25MHZ(10PF,20PPM)7M25000149'     | 'TXC'   | '7M25000149'                           | 'EP(V1)'     | ''        | 'IO'  | ''      | 'S3I-NICK'       | 'TXC_7M25000149.pdf'                           | '7M25000149.msg' | ''            | ''     | ''  | ''         | ''      | '20220630'
 '27MHZ'    | 'SMLF'    | 'MISC'   | 'BG627000012'(!) = ''              | ''             | 'BG627000012' |'X_4S_7M25000083_3-2X2-5'| ''          | 'XTAL SMD 27MHZ(+-10PPM,10PF)7M27000008'   | 'TXC'   | '7M27000008'                           | 'EP'         | 'EP'      | 'IO'  | ''      | 'S7G-LINK'       | 'TXC_7M27000008.pdf'                           | '7M27000008.msg' | ''            | ''     | ''  | ''         | ''      | '20221129'
 '27MHZ'    | 'SMLF'    | 'EMPTY'  | 'BG627000012'(!) = ''              | ''             | 'BG627000012' |'X_4S_7M25000083_3-2X2-5'| ''          | 'XTAL SMD 27MHZ(+-10PPM,10PF)7M27000008'   | 'TXC'   | '7M27000008'                           | 'EP'         | 'EP'      | 'IO'  | ''      | 'S7G-LINK'       | 'TXC_7M27000008.pdf'                           | '7M27000008.msg' | ''            | ''     | ''  | ''         | ''      | '20221129'
 '20MHZ'    | 'SMLF'    | 'MISC'   | 'BG620000024'(!) = ''              | ''             | 'BG620000024' |'X_4S_8Y40000010_2X1-6'| ''          | 'CRYSTAL SMD 20MHZ(+-10PPM,16PF)'          | 'TXC'   | '8Y20000005'                           | 'EP(V1)'     | ''        | 'IO'  | ''      | 'S7M-STEVE'      | 'TXC_8Y20000005.pdf'                           | ''               | ''            | ''     | ''  | ''         | ''      | '20221205'
 '20MHZ'    | 'SMLF'    | 'EMPTY'  | 'BG620000024'(!) = ''              | ''             | 'BG620000024' |'X_4S_8Y40000010_2X1-6'| ''          | 'CRYSTAL SMD 20MHZ(+-10PPM,16PF)'          | 'TXC'   | '8Y20000005'                           | 'EP(V1)'     | ''        | 'IO'  | ''      | 'S7M-STEVE'      | 'TXC_8Y20000005.pdf'                           | ''               | ''            | ''     | ''  | ''         | ''      | '20221205'
 '25MHZ'    | 'SMLF'    | 'MISC'   | 'BG6250000L4'(!) = ''              | ''             | 'BG6250000L4' |'OSC4_E3FB'| ''          | 'XTAL SMD 25MHZ(+-10PPM,8PF)E3SB25E000004' | 'HHE'   | 'E3SB25E000004E'                       | 'EP(V1)'     | 'EP(V1)'  | 'IO'  | ''      | 'F0TG-CART'      | 'HHE_E3SB25E000004E.pdf'                       | ''               | ''            | ''     | ''  | ''         | ''      | '20221226'
 '25MHZ'    | 'SMLF'    | 'EMPTY'  | 'BG6250000L4'(!) = ''              | ''             | 'BG6250000L4' |'OSC4_E3FB'| ''          | 'XTAL SMD 25MHZ(+-10PPM,8PF)E3SB25E000004' | 'HHE'   | 'E3SB25E000004E'                       | 'EP(V1)'     | 'EP(V1)'  | 'IO'  | ''      | 'F0TG-CART'      | 'HHE_E3SB25E000004E.pdf'                       | ''               | ''            | ''     | ''  | ''         | ''      | '20221226'
 '24MHZ'    | 'SMLF'    | 'MISC'   | 'BG6240000L9'(!) = ''               | ''               | 'BG6240000L9' |'X_4S_FL4000120_3-2X2-5'| ''          | 'XTAL SMD 24MHZ(+-30PPM,20PF)FL2400040'    | 'DDS'   | 'FL2400040'                            | 'EP(V1)'     | ''        | 'IO'  | ''      | 'F0EG-PATRICK'   | 'DDS_FL2400040.pdf'                            | ''               | ''            | ''     | ''  | ''         | ''      | '20230209'
 '24MHZ'    | 'SMLF'    | 'EMPTY'  | 'BG6240000L9'(!) = ''               | ''               | 'BG6240000L9' |'X_4S_FL4000120_3-2X2-5'| ''          | 'XTAL SMD 24MHZ(+-30PPM,20PF)FL2400040'    | 'DDS'   | 'FL2400040'                            | 'EP(V1)'     | ''        | 'IO'  | ''      | 'F0EG-PATRICK'   | 'DDS_FL2400040.pdf'                            | ''               | ''            | ''     | ''  | ''         | ''      | '20230209'

END_PART

END.

